(kicad_pcb
	(version 20260206)
	(generator "pcbnew")
	(generator_version "10.0")
	(general
		(thickness 1.6)
		(legacy_teardrops no)
	)
	(paper "A4")
	(title_block
		(title "timecard-production-celestica-r4006 — R4006-B0001-02_R01.brd")
		(comment 1 "Time Appliance Project (Time Card) / footprints 366-371 of 1113")
	)
	(layers
		(0 "F.Cu" signal "TOP")
		(4 "In1.Cu" signal "L02_GND1")
		(6 "In2.Cu" signal "L03_SIG1")
		(8 "In3.Cu" signal "L04_GND2")
		(10 "In4.Cu" signal "L05_VCC1")
		(12 "In5.Cu" signal "L06_VCC2")
		(14 "In6.Cu" signal "L07_GND3")
		(16 "In7.Cu" signal "L08_SIG2")
		(18 "In8.Cu" signal "L09_GND4")
		(2 "B.Cu" signal "BOTTOM")
		(9 "F.Adhes" user "F.Adhesive")
		(11 "B.Adhes" user "B.Adhesive")
		(13 "F.Paste" user "Package Geometry/Pastemask Top")
		(15 "B.Paste" user "Package Geometry/Pastemask Bottom")
		(5 "F.SilkS" user "Ref Des/Silkscreen Top")
		(7 "B.SilkS" user "Ref Des/Silkscreen Bottom")
		(1 "F.Mask" user "Board Geometry/Soldermask Top")
		(3 "B.Mask" user "Board Geometry/Soldermask Bottom")
		(17 "Dwgs.User" user "User.Drawings")
		(19 "Cmts.User" user "User.Comments")
		(21 "Eco1.User" user "User.Eco1")
		(23 "Eco2.User" user "User.Eco2")
		(25 "Edge.Cuts" user "Board Geometry/Outline")
		(27 "Margin" user)
		(31 "F.CrtYd" user "Package Geometry/Place Bound Top")
		(29 "B.CrtYd" user "Package Geometry/Place Bound Bottom")
		(35 "F.Fab" user "Ref Des/Assembly Top")
		(33 "B.Fab" user "Ref Des/Assembly Bottom")
	)
	(footprint ""
		(layer "F.Cu")
		(at 20.32 -29.21 180)
		(property "Reference" "R373"
			(at -2.794 -0.54737 0)
			(unlocked yes)
			(layer "F.SilkS")
			(effects
				(font
					(size 0.7874 0.5842)
					(thickness 0.1524)
				)
			)
		)
		(property "Value" "VAL*"
			(at 0.02032 2.13233 180)
			(unlocked yes)
			(layer "F.Fab")
			(hide yes)
			(effects
				(font
					(size 0.7874 0.5842)
					(thickness 0.1524)
				)
			)
		)
		(property "Device Type" "RESISTOR-G155-11000-01,100OHM,A"
			(at 0.008382 1.210564 180)
			(unlocked yes)
			(layer "F.Fab")
			(hide yes)
			(effects
				(font
					(size 0.7874 0.5842)
					(thickness 0.1524)
				)
			)
		)
		(property "User Part Number" "PARTNUM*"
			(at 0.02032 4.024884 180)
			(unlocked yes)
			(layer "Cmts.User")
			(hide yes)
			(effects
				(font
					(size 0.7874 0.5842)
					(thickness 0.1524)
				)
			)
		)
		(property "Tolerance" "TOL*"
			(at 0.044704 3.05435 180)
			(unlocked yes)
			(layer "Cmts.User")
			(hide yes)
			(effects
				(font
					(size 0.7874 0.5842)
					(thickness 0.1524)
				)
			)
		)
		(duplicate_pad_numbers_are_jumpers no)
		(fp_line
			(start 1.143 0.5588)
			(end 1.143 -0.5588)
			(stroke
				(width 0.1)
				(type default)
			)
			(layer "F.SilkS")
		)
		(fp_line
			(start 1.143 -0.5588)
			(end -1.143 -0.5588)
			(stroke
				(width 0.1)
				(type default)
			)
			(layer "F.SilkS")
		)
		(fp_line
			(start -1.143 0.5588)
			(end 1.143 0.5588)
			(stroke
				(width 0.1)
				(type default)
			)
			(layer "F.SilkS")
		)
		(fp_line
			(start -1.143 -0.5588)
			(end -1.143 0.5588)
			(stroke
				(width 0.1)
				(type default)
			)
			(layer "F.SilkS")
		)
		(fp_poly
			(pts
				(xy -1.143 0.5588) (xy 1.143 0.5588) (xy 1.143 -0.5588) (xy -1.143 -0.5588)
			)
			(stroke
				(width 0)
				(type default)
			)
			(fill no)
			(layer "F.CrtYd")
		)
		(fp_line
			(start 0.508 0.3048)
			(end 0.508 -0.3048)
			(stroke
				(width 0.1)
				(type default)
			)
			(layer "F.Fab")
		)
		(fp_line
			(start 0.508 -0.3048)
			(end -0.508 -0.3048)
			(stroke
				(width 0.1)
				(type default)
			)
			(layer "F.Fab")
		)
		(fp_line
			(start -0.508 0.3048)
			(end 0.508 0.3048)
			(stroke
				(width 0.1)
				(type default)
			)
			(layer "F.Fab")
		)
		(fp_line
			(start -0.508 -0.3048)
			(end -0.508 0.3048)
			(stroke
				(width 0.1)
				(type default)
			)
			(layer "F.Fab")
		)
		(pad "1" smd rect
			(at -0.5334 0 180)
			(size 0.7112 0.6096)
			(layers "F.Cu" "F.Mask" "F.Paste")
			(net "FPGA_OUT_SMA2_LED_RED_N")
		)
		(pad "2" smd rect
			(at 0.5334 0 180)
			(size 0.7112 0.6096)
			(layers "F.Cu" "F.Mask" "F.Paste")
			(net "UNNAMED_14_LED4PV14_I266_3")
		)
		(zone
			(layer "F.Cu")
			(hatch none 0.5)
			(connect_pads
				(clearance 0)
			)
			(min_thickness 0.25)
			(keepout
				(tracks not_allowed)
				(vias allowed)
				(pads allowed)
				(copperpour not_allowed)
				(footprints allowed)
			)
			(placement
				(enabled no)
				(sheetname "")
			)
			(fill
				(thermal_gap 0.5)
				(thermal_bridge_width 0.5)
				(island_removal_mode 0)
			)
			(polygon
				(pts
					(xy 20.3962 -29.5148) (xy 20.2438 -29.5148) (xy 20.2438 -28.9052) (xy 20.3962 -28.9052)
				)
			)
		)
		(zone
			(layer "F.Cu")
			(hatch none 0.5)
			(connect_pads
				(clearance 0)
			)
			(min_thickness 0.25)
			(keepout
				(tracks allowed)
				(vias not_allowed)
				(pads allowed)
				(copperpour not_allowed)
				(footprints allowed)
			)
			(placement
				(enabled no)
				(sheetname "")
			)
			(fill
				(thermal_gap 0.5)
				(thermal_bridge_width 0.5)
				(island_removal_mode 0)
			)
			(polygon
				(pts
					(xy 20.3962 -29.5148) (xy 20.2438 -29.5148) (xy 20.2438 -28.9052) (xy 20.3962 -28.9052)
				)
			)
		)
	)
	(footprint ""
		(layer "F.Cu")
		(at 128.6002 -65.9638)
		(property "Reference" "C189"
			(at 0.508 5.75437 0)
			(unlocked yes)
			(layer "F.SilkS")
			(effects
				(font
					(size 0.7874 0.5842)
					(thickness 0.1524)
				)
			)
		)
		(property "Value" "VAL*"
			(at 0.0762 2.067306 0)
			(unlocked yes)
			(layer "F.Fab")
			(hide yes)
			(effects
				(font
					(size 0.7874 0.5842)
					(thickness 0.1524)
				)
			)
		)
		(property "Tolerance" "TOL*"
			(at 0.0762 3.032506 0)
			(unlocked yes)
			(layer "Cmts.User")
			(hide yes)
			(effects
				(font
					(size 0.7874 0.5842)
					(thickness 0.1524)
				)
			)
		)
		(property "User Part Number" "PARTNUM*"
			(at 0.1016 4.023106 0)
			(unlocked yes)
			(layer "Cmts.User")
			(hide yes)
			(effects
				(font
					(size 0.7874 0.5842)
					(thickness 0.1524)
				)
			)
		)
		(property "Device Type" "CAPACITOR-G105-0B104-EK,0.1UF,A"
			(at 0.0508 1.127506 0)
			(unlocked yes)
			(layer "F.Fab")
			(hide yes)
			(effects
				(font
					(size 0.7874 0.5842)
					(thickness 0.1524)
				)
			)
		)
		(duplicate_pad_numbers_are_jumpers no)
		(fp_line
			(start -1.143 -0.5588)
			(end -1.143 0.5588)
			(stroke
				(width 0.1)
				(type default)
			)
			(layer "F.SilkS")
		)
		(fp_line
			(start -1.143 0.5588)
			(end 1.143 0.5588)
			(stroke
				(width 0.1)
				(type default)
			)
			(layer "F.SilkS")
		)
		(fp_line
			(start 1.143 -0.5588)
			(end -1.143 -0.5588)
			(stroke
				(width 0.1)
				(type default)
			)
			(layer "F.SilkS")
		)
		(fp_line
			(start 1.143 0.5588)
			(end 1.143 -0.5588)
			(stroke
				(width 0.1)
				(type default)
			)
			(layer "F.SilkS")
		)
		(fp_rect
			(start 1.143 -0.5588)
			(end -1.143 0.5588)
			(stroke
				(width 0)
				(type default)
			)
			(fill no)
			(layer "F.CrtYd")
		)
		(fp_line
			(start -0.508 -0.3048)
			(end -0.508 0.3048)
			(stroke
				(width 0.1)
				(type default)
			)
			(layer "F.Fab")
		)
		(fp_line
			(start -0.508 0.3048)
			(end 0.508 0.3048)
			(stroke
				(width 0.1)
				(type default)
			)
			(layer "F.Fab")
		)
		(fp_line
			(start 0.508 -0.3048)
			(end -0.508 -0.3048)
			(stroke
				(width 0.1)
				(type default)
			)
			(layer "F.Fab")
		)
		(fp_line
			(start 0.508 0.3048)
			(end 0.508 -0.3048)
			(stroke
				(width 0.1)
				(type default)
			)
			(layer "F.Fab")
		)
		(pad "1" smd rect
			(at -0.5334 0)
			(size 0.7112 0.6096)
			(layers "F.Cu" "F.Mask" "F.Paste")
			(net "XP1R8V_VIN")
		)
		(pad "2" smd rect
			(at 0.5334 0)
			(size 0.7112 0.6096)
			(layers "F.Cu" "F.Mask" "F.Paste")
			(net "SG")
		)
		(zone
			(layer "F.Cu")
			(hatch none 0.5)
			(connect_pads
				(clearance 0)
			)
			(min_thickness 0.25)
			(keepout
				(tracks allowed)
				(vias not_allowed)
				(pads allowed)
				(copperpour not_allowed)
				(footprints allowed)
			)
			(placement
				(enabled no)
				(sheetname "")
			)
			(fill
				(thermal_gap 0.5)
				(thermal_bridge_width 0.5)
				(island_removal_mode 0)
			)
			(polygon
				(pts
					(xy 128.6764 -66.2686) (xy 128.524 -66.2686) (xy 128.524 -65.659) (xy 128.6764 -65.659)
				)
			)
		)
	)
	(footprint ""
		(layer "F.Cu")
		(at 101.854 -26.67 90)
		(property "Reference" "C254"
			(at 0.508 -2.11963 90)
			(unlocked yes)
			(layer "F.SilkS")
			(effects
				(font
					(size 0.7874 0.5842)
					(thickness 0.1524)
				)
			)
		)
		(property "Value" "VAL*"
			(at 0.0762 2.067306 90)
			(unlocked yes)
			(layer "F.Fab")
			(hide yes)
			(effects
				(font
					(size 0.7874 0.5842)
					(thickness 0.1524)
				)
			)
		)
		(property "Tolerance" "TOL*"
			(at 0.0762 3.032506 90)
			(unlocked yes)
			(layer "Cmts.User")
			(hide yes)
			(effects
				(font
					(size 0.7874 0.5842)
					(thickness 0.1524)
				)
			)
		)
		(property "User Part Number" "PARTNUM*"
			(at 0.1016 4.023106 90)
			(unlocked yes)
			(layer "Cmts.User")
			(hide yes)
			(effects
				(font
					(size 0.7874 0.5842)
					(thickness 0.1524)
				)
			)
		)
		(property "Device Type" "CAPACITOR-G105-0B104-CK,0.1UF,A"
			(at 0.0508 1.127506 90)
			(unlocked yes)
			(layer "F.Fab")
			(hide yes)
			(effects
				(font
					(size 0.7874 0.5842)
					(thickness 0.1524)
				)
			)
		)
		(duplicate_pad_numbers_are_jumpers no)
		(fp_line
			(start 1.143 -0.5588)
			(end -1.143 -0.5588)
			(stroke
				(width 0.1)
				(type default)
			)
			(layer "F.SilkS")
		)
		(fp_line
			(start -1.143 -0.5588)
			(end -1.143 0.5588)
			(stroke
				(width 0.1)
				(type default)
			)
			(layer "F.SilkS")
		)
		(fp_line
			(start 1.143 0.5588)
			(end 1.143 -0.5588)
			(stroke
				(width 0.1)
				(type default)
			)
			(layer "F.SilkS")
		)
		(fp_line
			(start -1.143 0.5588)
			(end 1.143 0.5588)
			(stroke
				(width 0.1)
				(type default)
			)
			(layer "F.SilkS")
		)
		(fp_rect
			(start -1.143 -0.5588)
			(end 1.143 0.5588)
			(stroke
				(width 0)
				(type default)
			)
			(fill no)
			(layer "F.CrtYd")
		)
		(fp_line
			(start 0.508 -0.3048)
			(end -0.508 -0.3048)
			(stroke
				(width 0.1)
				(type default)
			)
			(layer "F.Fab")
		)
		(fp_line
			(start -0.508 -0.3048)
			(end -0.508 0.3048)
			(stroke
				(width 0.1)
				(type default)
			)
			(layer "F.Fab")
		)
		(fp_line
			(start 0.508 0.3048)
			(end 0.508 -0.3048)
			(stroke
				(width 0.1)
				(type default)
			)
			(layer "F.Fab")
		)
		(fp_line
			(start -0.508 0.3048)
			(end 0.508 0.3048)
			(stroke
				(width 0.1)
				(type default)
			)
			(layer "F.Fab")
		)
		(pad "1" smd rect
			(at -0.5334 0 90)
			(size 0.7112 0.6096)
			(layers "F.Cu" "F.Mask" "F.Paste")
			(net "OSC_125M_CLKN")
		)
		(pad "2" smd rect
			(at 0.5334 0 90)
			(size 0.7112 0.6096)
			(layers "F.Cu" "F.Mask" "F.Paste")
			(net "MHZ125CLKN_CLKIN")
		)
		(zone
			(layer "F.Cu")
			(hatch none 0.5)
			(connect_pads
				(clearance 0)
			)
			(min_thickness 0.25)
			(keepout
				(tracks allowed)
				(vias not_allowed)
				(pads allowed)
				(copperpour not_allowed)
				(footprints allowed)
			)
			(placement
				(enabled no)
				(sheetname "")
			)
			(fill
				(thermal_gap 0.5)
				(thermal_bridge_width 0.5)
				(island_removal_mode 0)
			)
			(polygon
				(pts
					(xy 101.5492 -26.5938) (xy 102.1588 -26.5938) (xy 102.1588 -26.7462) (xy 101.5492 -26.7462)
				)
			)
		)
	)
	(footprint ""
		(layer "F.Cu")
		(at 52.451 -131.064)
		(property "Reference" "SP27"
			(at 0 0 0)
			(layer "F.SilkS")
			(hide yes)
			(effects
				(font
					(size 1.27 1.27)
				)
			)
		)
		(property "Value" ""
			(at 0 0 0)
			(layer "F.Fab")
			(effects
				(font
					(size 1.27 1.27)
				)
			)
		)
		(duplicate_pad_numbers_are_jumpers no)
	)
	(footprint ""
		(layer "F.Cu")
		(at 9.5758 -68.201032 90)
		(property "Reference" "R392"
			(at 3.553968 -0.64643 90)
			(unlocked yes)
			(layer "F.SilkS")
			(effects
				(font
					(size 0.7874 0.5842)
					(thickness 0.1524)
				)
			)
		)
		(property "Value" "VAL*"
			(at 0.02032 2.13233 90)
			(unlocked yes)
			(layer "F.Fab")
			(hide yes)
			(effects
				(font
					(size 0.7874 0.5842)
					(thickness 0.1524)
				)
			)
		)
		(property "Tolerance" "TOL*"
			(at 0.044704 3.05435 90)
			(unlocked yes)
			(layer "Cmts.User")
			(hide yes)
			(effects
				(font
					(size 0.7874 0.5842)
					(thickness 0.1524)
				)
			)
		)
		(property "User Part Number" "PARTNUM*"
			(at 0.02032 4.024884 90)
			(unlocked yes)
			(layer "Cmts.User")
			(hide yes)
			(effects
				(font
					(size 0.7874 0.5842)
					(thickness 0.1524)
				)
			)
		)
		(property "Device Type" "RESISTOR-G155-133R0-01,33OHM,1%"
			(at 0.008382 1.210564 90)
			(unlocked yes)
			(layer "F.Fab")
			(hide yes)
			(effects
				(font
					(size 0.7874 0.5842)
					(thickness 0.1524)
				)
			)
		)
		(duplicate_pad_numbers_are_jumpers no)
		(fp_line
			(start 1.143 -0.5588)
			(end -1.143 -0.5588)
			(stroke
				(width 0.1)
				(type default)
			)
			(layer "F.SilkS")
		)
		(fp_line
			(start -1.143 -0.5588)
			(end -1.143 0.5588)
			(stroke
				(width 0.1)
				(type default)
			)
			(layer "F.SilkS")
		)
		(fp_line
			(start 1.143 0.5588)
			(end 1.143 -0.5588)
			(stroke
				(width 0.1)
				(type default)
			)
			(layer "F.SilkS")
		)
		(fp_line
			(start -1.143 0.5588)
			(end 1.143 0.5588)
			(stroke
				(width 0.1)
				(type default)
			)
			(layer "F.SilkS")
		)
		(fp_rect
			(start -1.143 -0.5588)
			(end 1.143 0.5588)
			(stroke
				(width 0)
				(type default)
			)
			(fill no)
			(layer "F.CrtYd")
		)
		(fp_line
			(start 0.508 -0.3048)
			(end -0.508 -0.3048)
			(stroke
				(width 0.1)
				(type default)
			)
			(layer "F.Fab")
		)
		(fp_line
			(start -0.508 -0.3048)
			(end -0.508 0.3048)
			(stroke
				(width 0.1)
				(type default)
			)
			(layer "F.Fab")
		)
		(fp_line
			(start 0.508 0.3048)
			(end 0.508 -0.3048)
			(stroke
				(width 0.1)
				(type default)
			)
			(layer "F.Fab")
		)
		(fp_line
			(start -0.508 0.3048)
			(end 0.508 0.3048)
			(stroke
				(width 0.1)
				(type default)
			)
			(layer "F.Fab")
		)
		(pad "1" smd rect
			(at -0.5334 0 90)
			(size 0.7112 0.6096)
			(layers "F.Cu" "F.Mask" "F.Paste")
			(net "SMA3_LED_GREEN_N")
		)
		(pad "2" smd rect
			(at 0.5334 0 90)
			(size 0.7112 0.6096)
			(layers "F.Cu" "F.Mask" "F.Paste")
			(net "UNNAMED_14_LED4PV14_I267_4")
		)
		(zone
			(layer "F.Cu")
			(hatch none 0.5)
			(connect_pads
				(clearance 0)
			)
			(min_thickness 0.25)
			(keepout
				(tracks not_allowed)
				(vias allowed)
				(pads allowed)
				(copperpour not_allowed)
				(footprints allowed)
			)
			(placement
				(enabled no)
				(sheetname "")
			)
			(fill
				(thermal_gap 0.5)
				(thermal_bridge_width 0.5)
				(island_removal_mode 0)
			)
			(polygon
				(pts
					(xy 9.271 -68.124832) (xy 9.8806 -68.124832) (xy 9.8806 -68.277232) (xy 9.271 -68.277232)
				)
			)
		)
		(zone
			(layer "F.Cu")
			(hatch none 0.5)
			(connect_pads
				(clearance 0)
			)
			(min_thickness 0.25)
			(keepout
				(tracks allowed)
				(vias not_allowed)
				(pads allowed)
				(copperpour not_allowed)
				(footprints allowed)
			)
			(placement
				(enabled no)
				(sheetname "")
			)
			(fill
				(thermal_gap 0.5)
				(thermal_bridge_width 0.5)
				(island_removal_mode 0)
			)
			(polygon
				(pts
					(xy 9.271 -68.124832) (xy 9.8806 -68.124832) (xy 9.8806 -68.277232) (xy 9.271 -68.277232)
				)
			)
		)
	)
	(footprint ""
		(layer "F.Cu")
		(at 126.492 -35.179 180)
		(property "Reference" "R221"
			(at -2.921 -1.56337 0)
			(unlocked yes)
			(layer "F.SilkS")
			(effects
				(font
					(size 0.7874 0.5842)
					(thickness 0.1524)
				)
			)
		)
		(property "Value" "VAL*"
			(at 0.02032 2.13233 180)
			(unlocked yes)
			(layer "F.Fab")
			(hide yes)
			(effects
				(font
					(size 0.7874 0.5842)
					(thickness 0.1524)
				)
			)
		)
		(property "Device Type" "RESISTOR-G155-11000-01,100OHM,A"
			(at 0.008382 1.210564 180)
			(unlocked yes)
			(layer "F.Fab")
			(hide yes)
			(effects
				(font
					(size 0.7874 0.5842)
					(thickness 0.1524)
				)
			)
		)
		(property "User Part Number" "PARTNUM*"
			(at 0.02032 4.024884 180)
			(unlocked yes)
			(layer "Cmts.User")
			(hide yes)
			(effects
				(font
					(size 0.7874 0.5842)
					(thickness 0.1524)
				)
			)
		)
		(property "Tolerance" "TOL*"
			(at 0.044704 3.05435 180)
			(unlocked yes)
			(layer "Cmts.User")
			(hide yes)
			(effects
				(font
					(size 0.7874 0.5842)
					(thickness 0.1524)
				)
			)
		)
		(duplicate_pad_numbers_are_jumpers no)
		(fp_line
			(start 1.143 0.5588)
			(end 1.143 -0.5588)
			(stroke
				(width 0.1)
				(type default)
			)
			(layer "F.SilkS")
		)
		(fp_line
			(start 1.143 -0.5588)
			(end -1.143 -0.5588)
			(stroke
				(width 0.1)
				(type default)
			)
			(layer "F.SilkS")
		)
		(fp_line
			(start -1.143 0.5588)
			(end 1.143 0.5588)
			(stroke
				(width 0.1)
				(type default)
			)
			(layer "F.SilkS")
		)
		(fp_line
			(start -1.143 -0.5588)
			(end -1.143 0.5588)
			(stroke
				(width 0.1)
				(type default)
			)
			(layer "F.SilkS")
		)
		(fp_rect
			(start 1.143 0.5588)
			(end -1.143 -0.5588)
			(stroke
				(width 0)
				(type default)
			)
			(fill no)
			(layer "F.CrtYd")
		)
		(fp_line
			(start 0.508 0.3048)
			(end 0.508 -0.3048)
			(stroke
				(width 0.1)
				(type default)
			)
			(layer "F.Fab")
		)
		(fp_line
			(start 0.508 -0.3048)
			(end -0.508 -0.3048)
			(stroke
				(width 0.1)
				(type default)
			)
			(layer "F.Fab")
		)
		(fp_line
			(start -0.508 0.3048)
			(end 0.508 0.3048)
			(stroke
				(width 0.1)
				(type default)
			)
			(layer "F.Fab")
		)
		(fp_line
			(start -0.508 -0.3048)
			(end -0.508 0.3048)
			(stroke
				(width 0.1)
				(type default)
			)
			(layer "F.Fab")
		)
		(pad "1" smd rect
			(at -0.5334 0 180)
			(size 0.7112 0.6096)
			(layers "F.Cu" "F.Mask" "F.Paste")
			(net "XP3R3V_FPGA")
		)
		(pad "2" smd rect
			(at 0.5334 0 180)
			(size 0.7112 0.6096)
			(layers "F.Cu" "F.Mask" "F.Paste")
			(net "FPGA_M2")
		)
		(zone
			(layer "F.Cu")
			(hatch none 0.5)
			(connect_pads
				(clearance 0)
			)
			(min_thickness 0.25)
			(keepout
				(tracks allowed)
				(vias not_allowed)
				(pads allowed)
				(copperpour not_allowed)
				(footprints allowed)
			)
			(placement
				(enabled no)
				(sheetname "")
			)
			(fill
				(thermal_gap 0.5)
				(thermal_bridge_width 0.5)
				(island_removal_mode 0)
			)
			(polygon
				(pts
					(xy 126.4158 -35.4838) (xy 126.4158 -34.8742) (xy 126.5682 -34.8742) (xy 126.5682 -35.4838)
				)
			)
		)
	)
)
